(kicad_pcb
	(version 20260206)
	(generator "pcbnew")
	(generator_version "10.0")
	(general
		(thickness 1.6)
		(legacy_teardrops no)
	)
	(paper "A4")
	(title_block
		(title "01162023_DA0F0TEBIF0_F0T_Expander_BD_F_brd_V02_OCP.brd")
		(comment 1 "Grand Teton / footprints 2493-2495 of 9728")
	)
	(layers
		(0 "F.Cu" signal "TOP")
		(4 "In1.Cu" signal "GND")
		(6 "In2.Cu" signal "VCC")
		(8 "In3.Cu" signal "VCC1")
		(10 "In4.Cu" signal "GND1")
		(12 "In5.Cu" signal "IN1")
		(14 "In6.Cu" signal "GND2")
		(16 "In7.Cu" signal "IN2")
		(18 "In8.Cu" signal "GND3")
		(20 "In9.Cu" signal "IN3")
		(22 "In10.Cu" signal "GND4")
		(24 "In11.Cu" signal "IN4")
		(26 "In12.Cu" signal "GND5")
		(28 "In13.Cu" signal "IN5")
		(30 "In14.Cu" signal "GND6")
		(32 "In15.Cu" signal "IN6")
		(34 "In16.Cu" signal "GND7")
		(2 "B.Cu" signal "BOTTOM")
		(9 "F.Adhes" user "F.Adhesive")
		(11 "B.Adhes" user "B.Adhesive")
		(13 "F.Paste" user "Package Geometry/Pastemask Top")
		(15 "B.Paste" user "Package Geometry/Pastemask Bottom")
		(5 "F.SilkS" user "Ref Des/Silkscreen Top")
		(7 "B.SilkS" user "Ref Des/Silkscreen Bottom")
		(1 "F.Mask" user "Board Geometry/Soldermask Top")
		(3 "B.Mask" user "Board Geometry/Soldermask Bottom")
		(17 "Dwgs.User" user "User.Drawings")
		(19 "Cmts.User" user "User.Comments")
		(21 "Eco1.User" user "User.Eco1")
		(23 "Eco2.User" user "User.Eco2")
		(25 "Edge.Cuts" user "Board Geometry/Outline")
		(27 "Margin" user)
		(31 "F.CrtYd" user "Package Geometry/Place Bound Top")
		(29 "B.CrtYd" user "Package Geometry/Place Bound Bottom")
		(35 "F.Fab" user "Ref Des/Assembly Top")
		(33 "B.Fab" user "Ref Des/Assembly Bottom")
	)
	(footprint ""
		(layer "F.Cu")
		(at 237.332012 -257.975862 -90)
		(property "Reference" "R6531"
			(at 0 0 270)
			(layer "F.SilkS")
			(hide yes)
			(effects
				(font
					(size 1.27 1.27)
				)
			)
		)
		(property "Value" ""
			(at 0 0 270)
			(layer "F.Fab")
			(effects
				(font
					(size 1.27 1.27)
				)
			)
		)
		(duplicate_pad_numbers_are_jumpers no)
		(fp_line
			(start -0.7874 0.4064)
			(end -0.7874 -0.4064)
			(stroke
				(width 0.1524)
				(type default)
			)
			(layer "F.SilkS")
		)
		(fp_line
			(start 0.7874 0.4064)
			(end -0.7874 0.4064)
			(stroke
				(width 0.1524)
				(type default)
			)
			(layer "F.SilkS")
		)
		(fp_line
			(start -0.7874 -0.4064)
			(end 0.7874 -0.4064)
			(stroke
				(width 0.1524)
				(type default)
			)
			(layer "F.SilkS")
		)
		(fp_line
			(start 0.7874 -0.4064)
			(end 0.7874 0.4064)
			(stroke
				(width 0.1524)
				(type default)
			)
			(layer "F.SilkS")
		)
		(fp_line
			(start -0.67945 0.3048)
			(end -0.67945 -0.305054)
			(stroke
				(width 0.1)
				(type default)
			)
			(layer "F.Fab")
		)
		(fp_line
			(start -0.12065 0.3048)
			(end -0.67945 0.3048)
			(stroke
				(width 0.1)
				(type default)
			)
			(layer "F.Fab")
		)
		(fp_line
			(start 0.120396 0.3048)
			(end 0.120396 0.2794)
			(stroke
				(width 0.1)
				(type default)
			)
			(layer "F.Fab")
		)
		(fp_line
			(start 0.67945 0.3048)
			(end 0.120396 0.3048)
			(stroke
				(width 0.1)
				(type default)
			)
			(layer "F.Fab")
		)
		(fp_line
			(start -0.12065 0.2794)
			(end -0.12065 0.3048)
			(stroke
				(width 0.1)
				(type default)
			)
			(layer "F.Fab")
		)
		(fp_line
			(start 0.120396 0.2794)
			(end -0.12065 0.2794)
			(stroke
				(width 0.1)
				(type default)
			)
			(layer "F.Fab")
		)
		(fp_line
			(start -0.12065 -0.2794)
			(end 0.12065 -0.2794)
			(stroke
				(width 0.1)
				(type default)
			)
			(layer "F.Fab")
		)
		(fp_line
			(start 0.12065 -0.2794)
			(end 0.12065 -0.3048)
			(stroke
				(width 0.1)
				(type default)
			)
			(layer "F.Fab")
		)
		(fp_line
			(start 0.12065 -0.3048)
			(end 0.67945 -0.3048)
			(stroke
				(width 0.1)
				(type default)
			)
			(layer "F.Fab")
		)
		(fp_line
			(start 0.67945 -0.3048)
			(end 0.67945 0.3048)
			(stroke
				(width 0.1)
				(type default)
			)
			(layer "F.Fab")
		)
		(fp_line
			(start -0.67945 -0.305054)
			(end -0.12065 -0.305054)
			(stroke
				(width 0.1)
				(type default)
			)
			(layer "F.Fab")
		)
		(fp_line
			(start -0.12065 -0.305054)
			(end -0.12065 -0.2794)
			(stroke
				(width 0.1)
				(type default)
			)
			(layer "F.Fab")
		)
		(pad "1" smd circle
			(at -0.40005 0 270)
			(size 0 0)
			(layers "F.Cu" "F.Mask" "F.Paste")
			(net "P1V25_SERDES_VDDPLL_PEX2")
		)
		(pad "2" smd circle
			(at 0.40005 0 270)
			(size 0 0)
			(layers "F.Cu" "F.Mask" "F.Paste")
			(net "P1V25_SERDES_VDDPLL_PEX2_C8")
		)
	)
	(footprint ""
		(layer "F.Cu")
		(at 147.394168 -34.248852)
		(property "Reference" "R5664"
			(at 0 0 0)
			(layer "F.SilkS")
			(hide yes)
			(effects
				(font
					(size 1.27 1.27)
				)
			)
		)
		(property "Value" ""
			(at 0 0 0)
			(layer "F.Fab")
			(effects
				(font
					(size 1.27 1.27)
				)
			)
		)
		(duplicate_pad_numbers_are_jumpers no)
		(fp_line
			(start -0.7874 -0.4064)
			(end 0.7874 -0.4064)
			(stroke
				(width 0.1524)
				(type default)
			)
			(layer "F.SilkS")
		)
		(fp_line
			(start -0.7874 0.4064)
			(end -0.7874 -0.4064)
			(stroke
				(width 0.1524)
				(type default)
			)
			(layer "F.SilkS")
		)
		(fp_line
			(start 0.7874 -0.4064)
			(end 0.7874 0.4064)
			(stroke
				(width 0.1524)
				(type default)
			)
			(layer "F.SilkS")
		)
		(fp_line
			(start 0.7874 0.4064)
			(end -0.7874 0.4064)
			(stroke
				(width 0.1524)
				(type default)
			)
			(layer "F.SilkS")
		)
		(fp_line
			(start -0.67945 -0.305054)
			(end -0.12065 -0.305054)
			(stroke
				(width 0.1)
				(type default)
			)
			(layer "F.Fab")
		)
		(fp_line
			(start -0.67945 0.3048)
			(end -0.67945 -0.305054)
			(stroke
				(width 0.1)
				(type default)
			)
			(layer "F.Fab")
		)
		(fp_line
			(start -0.12065 -0.305054)
			(end -0.12065 -0.2794)
			(stroke
				(width 0.1)
				(type default)
			)
			(layer "F.Fab")
		)
		(fp_line
			(start -0.12065 -0.2794)
			(end 0.12065 -0.2794)
			(stroke
				(width 0.1)
				(type default)
			)
			(layer "F.Fab")
		)
		(fp_line
			(start -0.12065 0.2794)
			(end -0.12065 0.3048)
			(stroke
				(width 0.1)
				(type default)
			)
			(layer "F.Fab")
		)
		(fp_line
			(start -0.12065 0.3048)
			(end -0.67945 0.3048)
			(stroke
				(width 0.1)
				(type default)
			)
			(layer "F.Fab")
		)
		(fp_line
			(start 0.120396 0.2794)
			(end -0.12065 0.2794)
			(stroke
				(width 0.1)
				(type default)
			)
			(layer "F.Fab")
		)
		(fp_line
			(start 0.120396 0.3048)
			(end 0.120396 0.2794)
			(stroke
				(width 0.1)
				(type default)
			)
			(layer "F.Fab")
		)
		(fp_line
			(start 0.12065 -0.3048)
			(end 0.67945 -0.3048)
			(stroke
				(width 0.1)
				(type default)
			)
			(layer "F.Fab")
		)
		(fp_line
			(start 0.12065 -0.2794)
			(end 0.12065 -0.3048)
			(stroke
				(width 0.1)
				(type default)
			)
			(layer "F.Fab")
		)
		(fp_line
			(start 0.67945 -0.3048)
			(end 0.67945 0.3048)
			(stroke
				(width 0.1)
				(type default)
			)
			(layer "F.Fab")
		)
		(fp_line
			(start 0.67945 0.3048)
			(end 0.120396 0.3048)
			(stroke
				(width 0.1)
				(type default)
			)
			(layer "F.Fab")
		)
		(pad "1" smd circle
			(at -0.40005 0)
			(size 0 0)
			(layers "F.Cu" "F.Mask" "F.Paste")
			(net "RST_SMB_SSD5_ISO_N")
		)
		(pad "2" smd circle
			(at 0.40005 0)
			(size 0 0)
			(layers "F.Cu" "F.Mask" "F.Paste")
			(net "P3V3_SSD5")
		)
	)
	(footprint ""
		(layer "F.Cu")
		(at 13.439394 -308.282086)
		(property "Reference" "R842"
			(at 0 0 0)
			(layer "F.SilkS")
			(hide yes)
			(effects
				(font
					(size 1.27 1.27)
				)
			)
		)
		(property "Value" ""
			(at 0 0 0)
			(layer "F.Fab")
			(effects
				(font
					(size 1.27 1.27)
				)
			)
		)
		(duplicate_pad_numbers_are_jumpers no)
		(fp_line
			(start -0.7874 -0.4064)
			(end 0.7874 -0.4064)
			(stroke
				(width 0.1524)
				(type default)
			)
			(layer "F.SilkS")
		)
		(fp_line
			(start -0.7874 0.4064)
			(end -0.7874 -0.4064)
			(stroke
				(width 0.1524)
				(type default)
			)
			(layer "F.SilkS")
		)
		(fp_line
			(start 0.7874 -0.4064)
			(end 0.7874 0.4064)
			(stroke
				(width 0.1524)
				(type default)
			)
			(layer "F.SilkS")
		)
		(fp_line
			(start 0.7874 0.4064)
			(end -0.7874 0.4064)
			(stroke
				(width 0.1524)
				(type default)
			)
			(layer "F.SilkS")
		)
		(fp_line
			(start -0.67945 -0.305054)
			(end -0.12065 -0.305054)
			(stroke
				(width 0.1)
				(type default)
			)
			(layer "F.Fab")
		)
		(fp_line
			(start -0.67945 0.3048)
			(end -0.67945 -0.305054)
			(stroke
				(width 0.1)
				(type default)
			)
			(layer "F.Fab")
		)
		(fp_line
			(start -0.12065 -0.305054)
			(end -0.12065 -0.2794)
			(stroke
				(width 0.1)
				(type default)
			)
			(layer "F.Fab")
		)
		(fp_line
			(start -0.12065 -0.2794)
			(end 0.12065 -0.2794)
			(stroke
				(width 0.1)
				(type default)
			)
			(layer "F.Fab")
		)
		(fp_line
			(start -0.12065 0.2794)
			(end -0.12065 0.3048)
			(stroke
				(width 0.1)
				(type default)
			)
			(layer "F.Fab")
		)
		(fp_line
			(start -0.12065 0.3048)
			(end -0.67945 0.3048)
			(stroke
				(width 0.1)
				(type default)
			)
			(layer "F.Fab")
		)
		(fp_line
			(start 0.120396 0.2794)
			(end -0.12065 0.2794)
			(stroke
				(width 0.1)
				(type default)
			)
			(layer "F.Fab")
		)
		(fp_line
			(start 0.120396 0.3048)
			(end 0.120396 0.2794)
			(stroke
				(width 0.1)
				(type default)
			)
			(layer "F.Fab")
		)
		(fp_line
			(start 0.12065 -0.3048)
			(end 0.67945 -0.3048)
			(stroke
				(width 0.1)
				(type default)
			)
			(layer "F.Fab")
		)
		(fp_line
			(start 0.12065 -0.2794)
			(end 0.12065 -0.3048)
			(stroke
				(width 0.1)
				(type default)
			)
			(layer "F.Fab")
		)
		(fp_line
			(start 0.67945 -0.3048)
			(end 0.67945 0.3048)
			(stroke
				(width 0.1)
				(type default)
			)
			(layer "F.Fab")
		)
		(fp_line
			(start 0.67945 0.3048)
			(end 0.120396 0.3048)
			(stroke
				(width 0.1)
				(type default)
			)
			(layer "F.Fab")
		)
		(pad "1" smd circle
			(at -0.40005 0)
			(size 0 0)
			(layers "F.Cu" "F.Mask" "F.Paste")
			(net "P1V25_PEX0_EN")
		)
		(pad "2" smd circle
			(at 0.40005 0)
			(size 0 0)
			(layers "F.Cu" "F.Mask" "F.Paste")
			(net "PWR_EN_PEX_R")
		)
	)
)
